(kicad_pcb
	(version 20260206)
	(generator "pcbnew")
	(generator_version "10.0")
	(general
		(thickness 1.6)
		(legacy_teardrops no)
	)
	(paper "A4")
	(title_block
		(title "Wiwynn_Tioga_Pass_MB.brd")
		(comment 1 "Tioga Pass / footprints 2453-2460 of 4770")
	)
	(layers
		(0 "F.Cu" signal "TOP")
		(4 "In1.Cu" signal "L2GND")
		(6 "In2.Cu" signal "L3")
		(8 "In3.Cu" signal "L4GND")
		(10 "In4.Cu" signal "L5")
		(12 "In5.Cu" signal "L6GND")
		(14 "In6.Cu" signal "L7VCC")
		(16 "In7.Cu" signal "L8VCC")
		(18 "In8.Cu" signal "L9GND")
		(20 "In9.Cu" signal "L10")
		(22 "In10.Cu" signal "L11GND")
		(24 "In11.Cu" signal "L12")
		(26 "In12.Cu" signal "L13GND")
		(2 "B.Cu" signal "BOTTOM")
		(9 "F.Adhes" user "F.Adhesive")
		(11 "B.Adhes" user "B.Adhesive")
		(13 "F.Paste" user "Package Geometry/Pastemask Top")
		(15 "B.Paste" user "Package Geometry/Pastemask Bottom")
		(5 "F.SilkS" user "Ref Des/Silkscreen Top")
		(7 "B.SilkS" user "Ref Des/Silkscreen Bottom")
		(1 "F.Mask" user "Board Geometry/Soldermask Top")
		(3 "B.Mask" user "Board Geometry/Soldermask Bottom")
		(17 "Dwgs.User" user "User.Drawings")
		(19 "Cmts.User" user "User.Comments")
		(21 "Eco1.User" user "User.Eco1")
		(23 "Eco2.User" user "User.Eco2")
		(25 "Edge.Cuts" user "Board Geometry/Outline")
		(27 "Margin" user)
		(31 "F.CrtYd" user "Package Geometry/Place Bound Top")
		(29 "B.CrtYd" user "Package Geometry/Place Bound Bottom")
		(35 "F.Fab" user "Ref Des/Assembly Top")
		(33 "B.Fab" user "Ref Des/Assembly Bottom")
	)
	(footprint ""
		(layer "B.Cu")
		(at 390.906 -84.709 180)
		(property "Reference" "R2L5"
			(at 0 0 0)
			(layer "B.SilkS")
			(hide yes)
			(effects
				(font
					(size 1.27 1.27)
				)
				(justify mirror)
			)
		)
		(property "Value" ""
			(at 0 0 0)
			(layer "B.Fab")
			(effects
				(font
					(size 1.27 1.27)
				)
				(justify mirror)
			)
		)
		(duplicate_pad_numbers_are_jumpers no)
		(fp_poly
			(pts
				(xy 0.2794 -0.1016) (xy -0.2794 -0.1016) (xy -0.2794 0.9906) (xy 0.2794 0.9906)
			)
			(stroke
				(width 0)
				(type default)
			)
			(fill no)
			(layer "B.CrtYd")
		)
		(fp_line
			(start 0.2794 0.9906)
			(end -0.2794 0.9906)
			(stroke
				(width 0.1)
				(type default)
			)
			(layer "B.Fab")
		)
		(fp_line
			(start 0.2794 -0.1016)
			(end 0.2794 0.9906)
			(stroke
				(width 0.1)
				(type default)
			)
			(layer "B.Fab")
		)
		(fp_line
			(start -0.2794 0.9906)
			(end -0.2794 -0.1016)
			(stroke
				(width 0.1)
				(type default)
			)
			(layer "B.Fab")
		)
		(fp_line
			(start -0.2794 -0.1016)
			(end 0.2794 -0.1016)
			(stroke
				(width 0.1)
				(type default)
			)
			(layer "B.Fab")
		)
		(pad "1" smd rect
			(at 0 0)
			(size 0.508 0.508)
			(layers "B.Cu" "B.Mask" "B.Paste")
			(net "P3V3_STBY")
		)
		(pad "2" smd rect
			(at 0 0.889)
			(size 0.508 0.508)
			(layers "B.Cu" "B.Mask" "B.Paste")
			(net "SGPIO_PCH_SSATA_LOAD_R")
		)
		(zone
			(layer "B.Cu")
			(hatch none 0.5)
			(connect_pads
				(clearance 0)
			)
			(min_thickness 0.25)
			(keepout
				(tracks not_allowed)
				(vias allowed)
				(pads allowed)
				(copperpour not_allowed)
				(footprints allowed)
			)
			(placement
				(enabled no)
				(sheetname "")
			)
			(fill
				(thermal_gap 0.5)
				(thermal_bridge_width 0.5)
				(island_removal_mode 0)
			)
			(polygon
				(pts
					(xy 390.652 -85.344) (xy 391.16 -85.344) (xy 391.16 -84.963) (xy 390.652 -84.963)
				)
			)
		)
		(zone
			(layer "B.Cu")
			(hatch none 0.5)
			(connect_pads
				(clearance 0)
			)
			(min_thickness 0.25)
			(keepout
				(tracks allowed)
				(vias not_allowed)
				(pads allowed)
				(copperpour not_allowed)
				(footprints allowed)
			)
			(placement
				(enabled no)
				(sheetname "")
			)
			(fill
				(thermal_gap 0.5)
				(thermal_bridge_width 0.5)
				(island_removal_mode 0)
			)
			(polygon
				(pts
					(xy 390.652 -84.963) (xy 391.16 -84.963) (xy 391.16 -85.344) (xy 390.652 -85.344)
				)
			)
		)
	)
	(footprint ""
		(layer "B.Cu")
		(at 463.55 -127.9398 180)
		(property "Reference" "R1M24"
			(at 0 0 0)
			(layer "B.SilkS")
			(hide yes)
			(effects
				(font
					(size 1.27 1.27)
				)
				(justify mirror)
			)
		)
		(property "Value" ""
			(at 0 0 0)
			(layer "B.Fab")
			(effects
				(font
					(size 1.27 1.27)
				)
				(justify mirror)
			)
		)
		(duplicate_pad_numbers_are_jumpers no)
		(fp_poly
			(pts
				(xy 0.2794 -0.1016) (xy -0.2794 -0.1016) (xy -0.2794 0.9906) (xy 0.2794 0.9906)
			)
			(stroke
				(width 0)
				(type default)
			)
			(fill no)
			(layer "B.CrtYd")
		)
		(fp_line
			(start 0.2794 0.9906)
			(end -0.2794 0.9906)
			(stroke
				(width 0.1)
				(type default)
			)
			(layer "B.Fab")
		)
		(fp_line
			(start 0.2794 -0.1016)
			(end 0.2794 0.9906)
			(stroke
				(width 0.1)
				(type default)
			)
			(layer "B.Fab")
		)
		(fp_line
			(start -0.2794 0.9906)
			(end -0.2794 -0.1016)
			(stroke
				(width 0.1)
				(type default)
			)
			(layer "B.Fab")
		)
		(fp_line
			(start -0.2794 -0.1016)
			(end 0.2794 -0.1016)
			(stroke
				(width 0.1)
				(type default)
			)
			(layer "B.Fab")
		)
		(pad "1" smd rect
			(at 0 0)
			(size 0.508 0.508)
			(layers "B.Cu" "B.Mask" "B.Paste")
			(net "P3V3_STBY")
		)
		(pad "2" smd rect
			(at 0 0.889)
			(size 0.508 0.508)
			(layers "B.Cu" "B.Mask" "B.Paste")
			(net "FM_OC0_USB_N")
		)
		(zone
			(layer "B.Cu")
			(hatch none 0.5)
			(connect_pads
				(clearance 0)
			)
			(min_thickness 0.25)
			(keepout
				(tracks not_allowed)
				(vias allowed)
				(pads allowed)
				(copperpour not_allowed)
				(footprints allowed)
			)
			(placement
				(enabled no)
				(sheetname "")
			)
			(fill
				(thermal_gap 0.5)
				(thermal_bridge_width 0.5)
				(island_removal_mode 0)
			)
			(polygon
				(pts
					(xy 463.296 -128.5748) (xy 463.804 -128.5748) (xy 463.804 -128.1938) (xy 463.296 -128.1938)
				)
			)
		)
		(zone
			(layer "B.Cu")
			(hatch none 0.5)
			(connect_pads
				(clearance 0)
			)
			(min_thickness 0.25)
			(keepout
				(tracks allowed)
				(vias not_allowed)
				(pads allowed)
				(copperpour not_allowed)
				(footprints allowed)
			)
			(placement
				(enabled no)
				(sheetname "")
			)
			(fill
				(thermal_gap 0.5)
				(thermal_bridge_width 0.5)
				(island_removal_mode 0)
			)
			(polygon
				(pts
					(xy 463.296 -128.1938) (xy 463.804 -128.1938) (xy 463.804 -128.5748) (xy 463.296 -128.5748)
				)
			)
		)
	)
	(footprint ""
		(layer "B.Cu")
		(at 419.6715 -71.9455)
		(property "Reference" "Q8F2"
			(at 1.16967 4.13004 270)
			(unlocked yes)
			(layer "B.SilkS")
			(effects
				(font
					(size 0.7874 0.5842)
					(thickness 0.1524)
				)
				(justify left mirror)
			)
		)
		(property "Value" ""
			(at 0 0 0)
			(layer "B.Fab")
			(effects
				(font
					(size 1.27 1.27)
				)
				(justify mirror)
			)
		)
		(duplicate_pad_numbers_are_jumpers no)
		(fp_line
			(start -1.778 -0.5715)
			(end -1.778 0.3175)
			(stroke
				(width 0.1524)
				(type default)
			)
			(layer "B.SilkS")
		)
		(fp_line
			(start -1.778 2.4765)
			(end -1.778 1.5875)
			(stroke
				(width 0.1524)
				(type default)
			)
			(layer "B.SilkS")
		)
		(fp_line
			(start -0.9525 -0.5715)
			(end -1.778 -0.5715)
			(stroke
				(width 0.1524)
				(type default)
			)
			(layer "B.SilkS")
		)
		(fp_line
			(start -0.9525 2.4765)
			(end -1.778 2.4765)
			(stroke
				(width 0.1524)
				(type default)
			)
			(layer "B.SilkS")
		)
		(fp_line
			(start -0.381 0.635)
			(end -0.381 1.27)
			(stroke
				(width 0.1524)
				(type default)
			)
			(layer "B.SilkS")
		)
		(fp_circle
			(center 0.9525 -0.9271)
			(end 1.0795 -0.9271)
			(stroke
				(width 0.254)
				(type default)
			)
			(fill no)
			(layer "B.SilkS")
		)
		(fp_poly
			(pts
				(xy -1.778 2.4765) (xy -0.381 2.4765) (xy -0.381 -0.5715) (xy -1.778 -0.5715)
			)
			(stroke
				(width 0)
				(type default)
			)
			(fill no)
			(layer "B.CrtYd")
		)
		(fp_line
			(start -1.778 -0.5715)
			(end -0.381 -0.5715)
			(stroke
				(width 0.1)
				(type default)
			)
			(layer "B.Fab")
		)
		(fp_line
			(start -1.778 2.4765)
			(end -1.778 -0.5715)
			(stroke
				(width 0.1)
				(type default)
			)
			(layer "B.Fab")
		)
		(fp_line
			(start -0.381 -0.5715)
			(end -0.381 2.4765)
			(stroke
				(width 0.1)
				(type default)
			)
			(layer "B.Fab")
		)
		(fp_line
			(start -0.381 2.4765)
			(end -1.778 2.4765)
			(stroke
				(width 0.1)
				(type default)
			)
			(layer "B.Fab")
		)
		(fp_circle
			(center 0.9525 -0.9271)
			(end 1.0795 -0.9271)
			(stroke
				(width 0.254)
				(type default)
			)
			(fill no)
			(layer "B.Fab")
		)
		(pad "1" smd rect
			(at 0 0 180)
			(size 1.143 0.508)
			(layers "B.Cu" "B.Mask" "B.Paste")
			(net "FM_FAST_PROCHOT_EN_N")
		)
		(pad "2" smd rect
			(at 0 1.905 180)
			(size 1.143 0.508)
			(layers "B.Cu" "B.Mask" "B.Paste")
			(net "GND")
		)
		(pad "3" smd rect
			(at -2.159 0.9525 180)
			(size 1.143 0.508)
			(layers "B.Cu" "B.Mask" "B.Paste")
			(net "FM_FAST_PROCHOT_EN")
		)
	)
	(footprint ""
		(layer "B.Cu")
		(at 20.3454 -78.0542 -90)
		(property "Reference" "R9P16"
			(at 0 0 90)
			(layer "B.SilkS")
			(hide yes)
			(effects
				(font
					(size 1.27 1.27)
				)
				(justify mirror)
			)
		)
		(property "Value" ""
			(at 0 0 90)
			(layer "B.Fab")
			(effects
				(font
					(size 1.27 1.27)
				)
				(justify mirror)
			)
		)
		(duplicate_pad_numbers_are_jumpers no)
		(fp_rect
			(start 0.2794 -0.1016)
			(end -0.2794 0.9906)
			(stroke
				(width 0)
				(type default)
			)
			(fill no)
			(layer "B.CrtYd")
		)
		(fp_line
			(start -0.2794 0.9906)
			(end -0.2794 -0.1016)
			(stroke
				(width 0.1)
				(type default)
			)
			(layer "B.Fab")
		)
		(fp_line
			(start 0.2794 0.9906)
			(end -0.2794 0.9906)
			(stroke
				(width 0.1)
				(type default)
			)
			(layer "B.Fab")
		)
		(fp_line
			(start -0.2794 -0.1016)
			(end 0.2794 -0.1016)
			(stroke
				(width 0.1)
				(type default)
			)
			(layer "B.Fab")
		)
		(fp_line
			(start 0.2794 -0.1016)
			(end 0.2794 0.9906)
			(stroke
				(width 0.1)
				(type default)
			)
			(layer "B.Fab")
		)
		(pad "1" smd rect
			(at 0 0 90)
			(size 0.508 0.508)
			(layers "B.Cu" "B.Mask" "B.Paste")
			(net "FM_P12V_HSC_ADR2")
		)
		(pad "2" smd rect
			(at 0 0.889 90)
			(size 0.508 0.508)
			(layers "B.Cu" "B.Mask" "B.Paste")
			(net "AGND_HSC")
		)
		(zone
			(layer "B.Cu")
			(hatch none 0.5)
			(connect_pads
				(clearance 0)
			)
			(min_thickness 0.25)
			(keepout
				(tracks not_allowed)
				(vias allowed)
				(pads allowed)
				(copperpour not_allowed)
				(footprints allowed)
			)
			(placement
				(enabled no)
				(sheetname "")
			)
			(fill
				(thermal_gap 0.5)
				(thermal_bridge_width 0.5)
				(island_removal_mode 0)
			)
			(polygon
				(pts
					(xy 20.0914 -77.8002) (xy 20.0914 -78.3082) (xy 19.7104 -78.3082) (xy 19.7104 -77.8002)
				)
			)
		)
		(zone
			(layer "B.Cu")
			(hatch none 0.5)
			(connect_pads
				(clearance 0)
			)
			(min_thickness 0.25)
			(keepout
				(tracks allowed)
				(vias not_allowed)
				(pads allowed)
				(copperpour not_allowed)
				(footprints allowed)
			)
			(placement
				(enabled no)
				(sheetname "")
			)
			(fill
				(thermal_gap 0.5)
				(thermal_bridge_width 0.5)
				(island_removal_mode 0)
			)
			(polygon
				(pts
					(xy 20.0914 -77.8002) (xy 20.0914 -78.3082) (xy 19.7104 -78.3082) (xy 19.7104 -77.8002)
				)
			)
		)
	)
	(footprint ""
		(layer "B.Cu")
		(at 416.3695 -30.988 90)
		(property "Reference" "C25W39"
			(at -0.97536 0.76708 180)
			(unlocked yes)
			(layer "B.SilkS")
			(effects
				(font
					(size 0.4064 0.254)
					(thickness 0.1524)
				)
				(justify mirror)
			)
		)
		(property "Value" ""
			(at 0 0 90)
			(layer "B.Fab")
			(effects
				(font
					(size 1.27 1.27)
				)
				(justify mirror)
			)
		)
		(duplicate_pad_numbers_are_jumpers no)
		(fp_poly
			(pts
				(xy 0.4953 -0.2032) (xy -0.4953 -0.2032) (xy -0.4953 1.6002) (xy 0.4953 1.6002)
			)
			(stroke
				(width 0)
				(type default)
			)
			(fill no)
			(layer "B.CrtYd")
		)
		(fp_line
			(start 0.4953 -0.2032)
			(end -0.4953 -0.2032)
			(stroke
				(width 0.1)
				(type default)
			)
			(layer "B.Fab")
		)
		(fp_line
			(start -0.4953 -0.2032)
			(end -0.4953 1.6002)
			(stroke
				(width 0.1)
				(type default)
			)
			(layer "B.Fab")
		)
		(fp_line
			(start 0.4953 1.6002)
			(end 0.4953 -0.2032)
			(stroke
				(width 0.1)
				(type default)
			)
			(layer "B.Fab")
		)
		(fp_line
			(start -0.4953 1.6002)
			(end 0.4953 1.6002)
			(stroke
				(width 0.1)
				(type default)
			)
			(layer "B.Fab")
		)
		(pad "1" smd rect
			(at 0 0 270)
			(size 0.762 0.889)
			(layers "B.Cu" "B.Mask" "B.Paste")
			(net "VCC_A_1V1")
		)
		(pad "2" smd rect
			(at 0 1.397 270)
			(size 0.762 0.889)
			(layers "B.Cu" "B.Mask" "B.Paste")
			(net "GND")
		)
		(zone
			(layer "B.Cu")
			(hatch none 0.5)
			(connect_pads
				(clearance 0)
			)
			(min_thickness 0.25)
			(keepout
				(tracks not_allowed)
				(vias allowed)
				(pads allowed)
				(copperpour not_allowed)
				(footprints allowed)
			)
			(placement
				(enabled no)
				(sheetname "")
			)
			(fill
				(thermal_gap 0.5)
				(thermal_bridge_width 0.5)
				(island_removal_mode 0)
			)
			(polygon
				(pts
					(xy 416.814 -31.369) (xy 416.814 -30.607) (xy 417.322 -30.607) (xy 417.322 -31.369)
				)
			)
		)
	)
	(footprint ""
		(layer "B.Cu")
		(at 458.851 -116.49202)
		(property "Reference" "C1M11"
			(at 0 0 0)
			(layer "B.SilkS")
			(hide yes)
			(effects
				(font
					(size 1.27 1.27)
				)
				(justify mirror)
			)
		)
		(property "Value" ""
			(at 0 0 0)
			(layer "B.Fab")
			(effects
				(font
					(size 1.27 1.27)
				)
				(justify mirror)
			)
		)
		(duplicate_pad_numbers_are_jumpers no)
		(fp_rect
			(start -0.3048 0.9906)
			(end 0.3048 -0.1016)
			(stroke
				(width 0)
				(type default)
			)
			(fill no)
			(layer "B.CrtYd")
		)
		(fp_line
			(start -0.3048 -0.1016)
			(end 0.3048 -0.1016)
			(stroke
				(width 0.1)
				(type default)
			)
			(layer "B.Fab")
		)
		(fp_line
			(start -0.3048 0.9906)
			(end -0.3048 -0.1016)
			(stroke
				(width 0.1)
				(type default)
			)
			(layer "B.Fab")
		)
		(fp_line
			(start 0.3048 -0.1016)
			(end 0.3048 0.9906)
			(stroke
				(width 0.1)
				(type default)
			)
			(layer "B.Fab")
		)
		(fp_line
			(start 0.3048 0.9906)
			(end -0.3048 0.9906)
			(stroke
				(width 0.1)
				(type default)
			)
			(layer "B.Fab")
		)
		(pad "1" smd rect
			(at 0 0 180)
			(size 0.508 0.508)
			(layers "B.Cu" "B.Mask" "B.Paste")
			(net "P3E_CPU0_PE3_OCP_TXN<13>")
		)
		(pad "2" smd rect
			(at 0 0.889 180)
			(size 0.508 0.508)
			(layers "B.Cu" "B.Mask" "B.Paste")
			(net "P3E_OCP_CPU0_PE3_C_TXN<13>")
		)
		(zone
			(layer "B.Cu")
			(hatch none 0.5)
			(connect_pads
				(clearance 0)
			)
			(min_thickness 0.25)
			(keepout
				(tracks not_allowed)
				(vias allowed)
				(pads allowed)
				(copperpour not_allowed)
				(footprints allowed)
			)
			(placement
				(enabled no)
				(sheetname "")
			)
			(fill
				(thermal_gap 0.5)
				(thermal_bridge_width 0.5)
				(island_removal_mode 0)
			)
			(polygon
				(pts
					(xy 458.597 -115.85702) (xy 459.105 -115.85702) (xy 459.105 -116.23802) (xy 458.597 -116.23802)
				)
			)
		)
		(zone
			(layer "B.Cu")
			(hatch none 0.5)
			(connect_pads
				(clearance 0)
			)
			(min_thickness 0.25)
			(keepout
				(tracks allowed)
				(vias not_allowed)
				(pads allowed)
				(copperpour not_allowed)
				(footprints allowed)
			)
			(placement
				(enabled no)
				(sheetname "")
			)
			(fill
				(thermal_gap 0.5)
				(thermal_bridge_width 0.5)
				(island_removal_mode 0)
			)
			(polygon
				(pts
					(xy 458.597 -115.85702) (xy 459.105 -115.85702) (xy 459.105 -116.23802) (xy 458.597 -116.23802)
				)
			)
		)
	)
	(footprint ""
		(layer "B.Cu")
		(at 475.361 -34.29)
		(property "Reference" "C1W17"
			(at -1.47828 0.78994 90)
			(unlocked yes)
			(layer "B.SilkS")
			(effects
				(font
					(size 0.4064 0.254)
					(thickness 0.1524)
				)
				(justify mirror)
			)
		)
		(property "Value" ""
			(at 0 0 0)
			(layer "B.Fab")
			(effects
				(font
					(size 1.27 1.27)
				)
				(justify mirror)
			)
		)
		(duplicate_pad_numbers_are_jumpers no)
		(fp_poly
			(pts
				(xy 0.7239 -0.2159) (xy -0.7239 -0.2159) (xy -0.7239 1.9939) (xy 0.7239 1.9939)
			)
			(stroke
				(width 0)
				(type default)
			)
			(fill no)
			(layer "B.CrtYd")
		)
		(fp_line
			(start -0.7239 -0.2159)
			(end 0.7239 -0.2159)
			(stroke
				(width 0.1)
				(type default)
			)
			(layer "B.Fab")
		)
		(fp_line
			(start -0.7239 1.9939)
			(end -0.7239 -0.2159)
			(stroke
				(width 0.1)
				(type default)
			)
			(layer "B.Fab")
		)
		(fp_line
			(start 0.7239 -0.2159)
			(end 0.7239 1.9939)
			(stroke
				(width 0.1)
				(type default)
			)
			(layer "B.Fab")
		)
		(fp_line
			(start 0.7239 1.9939)
			(end -0.7239 1.9939)
			(stroke
				(width 0.1)
				(type default)
			)
			(layer "B.Fab")
		)
		(pad "1" smd rect
			(at 0 0 180)
			(size 1.27 1.016)
			(layers "B.Cu" "B.Mask" "B.Paste")
			(net "P3V3_STBY_MNG_RMII")
		)
		(pad "2" smd rect
			(at 0 1.778 180)
			(size 1.27 1.016)
			(layers "B.Cu" "B.Mask" "B.Paste")
			(net "GND")
		)
		(zone
			(layer "B.Cu")
			(hatch none 0.5)
			(connect_pads
				(clearance 0)
			)
			(min_thickness 0.25)
			(keepout
				(tracks not_allowed)
				(vias allowed)
				(pads allowed)
				(copperpour not_allowed)
				(footprints allowed)
			)
			(placement
				(enabled no)
				(sheetname "")
			)
			(fill
				(thermal_gap 0.5)
				(thermal_bridge_width 0.5)
				(island_removal_mode 0)
			)
			(polygon
				(pts
					(xy 475.996 -33.782) (xy 474.726 -33.782) (xy 474.726 -33.02) (xy 475.996 -33.02)
				)
			)
		)
	)
	(footprint ""
		(layer "B.Cu")
		(at 489.08589 -33.674812 180)
		(property "Reference" "C1T11"
			(at 0 0 0)
			(layer "B.SilkS")
			(hide yes)
			(effects
				(font
					(size 1.27 1.27)
				)
				(justify mirror)
			)
		)
		(property "Value" ""
			(at 0 0 0)
			(layer "B.Fab")
			(effects
				(font
					(size 1.27 1.27)
				)
				(justify mirror)
			)
		)
		(duplicate_pad_numbers_are_jumpers no)
		(fp_poly
			(pts
				(xy -0.3048 -0.1016) (xy -0.3048 0.9906) (xy 0.3048 0.9906) (xy 0.3048 -0.1016)
			)
			(stroke
				(width 0)
				(type default)
			)
			(fill no)
			(layer "B.CrtYd")
		)
		(fp_line
			(start 0.3048 0.9906)
			(end -0.3048 0.9906)
			(stroke
				(width 0.1)
				(type default)
			)
			(layer "B.Fab")
		)
		(fp_line
			(start 0.3048 -0.1016)
			(end 0.3048 0.9906)
			(stroke
				(width 0.1)
				(type default)
			)
			(layer "B.Fab")
		)
		(fp_line
			(start -0.3048 0.9906)
			(end -0.3048 -0.1016)
			(stroke
				(width 0.1)
				(type default)
			)
			(layer "B.Fab")
		)
		(fp_line
			(start -0.3048 -0.1016)
			(end 0.3048 -0.1016)
			(stroke
				(width 0.1)
				(type default)
			)
			(layer "B.Fab")
		)
		(pad "1" smd rect
			(at 0 0)
			(size 0.508 0.508)
			(layers "B.Cu" "B.Mask" "B.Paste")
			(net "P3V3_STBY")
		)
		(pad "2" smd rect
			(at 0 0.889)
			(size 0.508 0.508)
			(layers "B.Cu" "B.Mask" "B.Paste")
			(net "GND")
		)
		(zone
			(layer "B.Cu")
			(hatch none 0.5)
			(connect_pads
				(clearance 0)
			)
			(min_thickness 0.25)
			(keepout
				(tracks not_allowed)
				(vias allowed)
				(pads allowed)
				(copperpour not_allowed)
				(footprints allowed)
			)
			(placement
				(enabled no)
				(sheetname "")
			)
			(fill
				(thermal_gap 0.5)
				(thermal_bridge_width 0.5)
				(island_removal_mode 0)
			)
			(polygon
				(pts
					(xy 488.83189 -34.309812) (xy 489.33989 -34.309812) (xy 489.33989 -33.928812) (xy 488.83189 -33.928812)
				)
			)
		)
		(zone
			(layer "B.Cu")
			(hatch none 0.5)
			(connect_pads
				(clearance 0)
			)
			(min_thickness 0.25)
			(keepout
				(tracks allowed)
				(vias not_allowed)
				(pads allowed)
				(copperpour not_allowed)
				(footprints allowed)
			)
			(placement
				(enabled no)
				(sheetname "")
			)
			(fill
				(thermal_gap 0.5)
				(thermal_bridge_width 0.5)
				(island_removal_mode 0)
			)
			(polygon
				(pts
					(xy 488.83189 -33.928812) (xy 489.33989 -33.928812) (xy 489.33989 -34.309812) (xy 488.83189 -34.309812)
				)
			)
		)
	)
)
